# T6G (Grand Teton) — schematic parts with pin connectivity, parts 8074–8080 of 8303; source: Cadence DE-HDL packaged netlist (pstxprt.dat, pstxnet.dat, pstchip.dat)

U18  LCMXO3LF9400C5BG484C  LCMXO3LF-9400C-5BG484C IC  pkg BGA484_0-8_19X19_H67  page 82  (pins 335-484 of 484)
  P5  PL21C  BI  = FM_APML_MUX2_SEL_R
  P6  PL21D  BI  = FM_APML_MUX2_OE_R_N
  P7  PL24D  BI  = FM_PVDDCR_CPU1_P0_R_EN
  P8  VCCIO3_2  POWER  = P3V3_AUX
  P9  GND38  POWER  = GND
  P10  GND39  POWER  = GND
  P11  GND40  POWER  = GND
  P12  GND41  POWER  = GND
  P13  GND42  POWER  = GND
  P14  GND43  POWER  = GND
  P15  VCCIO1_8  POWER  = P1V8_AUX
  P16  PR24B  BI  = FM_HDT_HDR_PWROK
  P17  PR24A  BI  = ESPI_CPU0_R1_D3
  P18  PR21D  BI  = ESPI_CPU0_R1_D2
  P19  PR21C  BI  = ESPI_CPU0_R1_D1
  P20  PR20D  BI  = ESPI_CPU0_ALERT_R_N
  P21  PR19B  BI  = FM_CPU0_HDT_CONN_TESTEN
  P22  PR20C  BI  = ESPI_CPU0_CS1_R_N
  R1  PL19B  BI  = FM_CPU0_CORETYPE0
  R2  PL21A  BI  = FM_CPU0_CORETYPE1
  R3  PL24A  BI  = FM_CPU1_SP5R1
  R4  PL24B  BI  = FM_CPU1_SP5R2
  R5  PL24C  BI  = FM_LED_PWRGD_PVDDCR_CPU1_P0
  R6  PL25C  BI  = PWRGD_CHAF_CPU1_R2
  R7  PL25D  BI  = FM_PWRGD_PVDDCR_CPU1_P0
  R8  GND44  POWER  = GND
  R9  VCCIO2_1  POWER  = P3V3_AUX
  R10  VCCIO2_2  POWER  = P3V3_AUX
  R11  VCCIO2_3  POWER  = P3V3_AUX
  R12  VCCIO2_4  POWER  = P3V3_AUX
  R13  VCCIO2_5  POWER  = P3V3_AUX
  R14  VCCIO2_6  POWER  = P3V3_AUX
  R15  GND45  POWER  = GND
  R16  PR26C  BI  = CPU1_JTAG_BUF_R_OE
  R17  PR26B  BI  = FM_PLD_CPU1_PRSNT_HDT
  R18  PR26A  BI  = CPU0_SPD_HOST_CTRL_R1_N
  R19  PR25D  BI  = SCM_USB_OC_R_N
  R20  PR25C  BI  = RST_RT_CPU0_P2_RESET_R2_N
  R21  PR20B  BI  = CLK_ESPI_CPU0_R1_CLK1
  R22  PR20A  BI  = FM_JTAG_BMC_OE
  T1  PL21B  BI  = FM_CPU1_CORETYPE1
  T2  PL25A  BI  = FM_CPU1_CORETYPE2
  T3  PL26A  BI  = FM_CPU1_SP5R3
  T4  PL26B  BI  = FM_CPU1_SP5R4
  T5  PL26C  BI  = FM_PDB_BUF_EN_N
  T6  PL26D  BI  = PWRGD_CHGL_CPU1_R2
  T7  PL30D  BI  = FM_PVDDCR_CPU1_P1_R_EN
  T8  PB8D  BI  = FM_PWRGD_PVDDCR_CPU1_P1
  T9  \pb16a||mclk||cclk\  BI  = FM_PWRGD_P1V8_RETIMER_CPU0
  T10  PB19C  BI  = FM_GPU_HSC_EN_R
  T11  PB22C  BI  = FM_LED_PWRGD_PVDD33_S5
  T12  PB27B  BI  = HPDB_HSC_PWRGD_ISO_R
  T13  PB32A  BI  = GPU_3V3IO_RSVD1_FFU_ISO_R
  T14  PB32B  BI  = RST_PERST_CPU0_SWB_N
  T15  PB43C  BI  = GPU_FPGA_BOOT_EN_R
  T16  PB46D  BI  = FM_P5V_EN
  T17  PR27C  BI  = RST_RT_CPU0_P3_RESET_R2_N
  T18  PR27B  BI  = P12V_ALL_PWROK_R
  T19  PR27A  BI  = RST_RT_CPU0_P3_PERST_R2_N
  T20  PR26D  BI  = SCM_IRQ_1V8_R_N
  T21  PR21B  BI  = ESPI_CPU0_R1_D0
  T22  PR21A  BI  = RST_ESPI_CPU0_RSTOUT_R_N
  U1  PL25B  BI  = FM_CPU0_SP5R3
  U2  \pl27a||pclkt3_0\  BI  = FM_CPU0_SP5R4
  U3  PL27C  BI  = E1S_0_PRSNT_R_N
  U4  PL27D  BI  = PWRGD_P5V_AUX_R3
  U5  PL28D  BI  = FM_LED_PWRGD_PVDDCR_CPU0_P0
  U6  PB5D  BI  = FM_PWRGD_PVDDIO_P0
  U7  PB8C  BI  = FM_UART_LS_EN
  U8  PB13D  BI  = FM_FPGA_DEBUG_SW_SPARE
  U9  \pb16b||so||spiso\  BI  = FM_PWRGD_P1V8_RETIMER_CPU1
  U10  PB19D  BI  = P12V_E1S_0_PWRGD
  U11  PB22D  BI  = P3V3_E1S_PWRGD_0_R
  U12  PB27C  BI  = NC
  U13  PB29D  BI  = HGX_DETECT_N_R
  U14  PB32C  BI  = RST_PERST_CPU1_SWB_N
  U15  PB38D  BI  = RST_BMC_FROM_SWB_ISO_R_N
  U16  PB43D  BI  = FM_NCSI_OCP_V3_2_R_OE
  U17  PR29C  BI  = FM_CPU0_FORCE_SELFREFRESH
  U18  PR28D  BI  = FM_PLD_CPU0_PRSNT_HDT
  U19  PR28C  BI  = FM_SPD_CPU0_SWITCH_CTRL_R_N
  U20  PR27D  BI  = BMC_JTAG_SEL_R
  U21  PR24D  BI  = FM_BIOS_POST_CMPLT_BUF_R_N
  U22  PR24C  BI  = FM_HDT_HDR_RESET_N
  V1  \pl27b||pclkc3_0\  BI  = FM_PRSNT_CPU0_R_N
  V2  GND46  POWER  = GND
  V3  VCCIO3_3  POWER  = P3V3_AUX
  V4  PL28C  BI  = FM_LED_PWRGD_PVDDCR_SOC_P0
  V5  PL30C  BI  = FM_PRSNT_CPU1_R_N
  V6  PB5C  BI  = FM_PVDDIO_P0_EN
  V7  PB11D  BI  = GPU_FPGA_RST_N
  V8  PB13C  BI  = PVDD18_S5_P1_R_EN
  V9  PB16C  BI  = FM_PVDD33_S5_EN
  V10  PB21A  BI  = FM_LED_PWRGD_PVDDCR_CPU0_P1
  V11  PB24C  BI  = RST_PERST_CPU1_SWB_1_N
  V12  PB27D  BI  = P3V3_E1S_0_EN_R
  V13  PB29C  BI  = GPU_3V3IO_RSVD4_ISO_R
  V14  PB32D  BI  = PRSNT_CABLE_GPU_A2_ISO_R_N
  V15  PB38C  BI  = BIC_MONITER_ISO_R
  V16  PB40D  BI  = RST_PERST_M2_0_R_N
  V17  PB46C  BI  = P3V3_OCP_V3_2_EN_R
  V18  PR30A  BI  = RST_SMB_RT_ROM_R2_N
  V19  PR29D  BI  = TP_FM_CLK_BUFFER_EN_R
  V20  VCCIO1_9  POWER  = P1V8_AUX
  V21  GND47  POWER  = GND
  V22  PR25A  BI  = FM_BIOS_USB_RECOVERY
  W1  PL28A  BI  = PWRGD_CHAF_CPU0_R2
  W2  PL28B  BI  = P12V_OCP_V3_1_PWRGD
  W3  PL29C  BI  = PVDDCR_SOC_P0_EN
  W4  PL30B  BI  = FM_PVDD11_S3_P0_EN
  W5  PB7D  BI  = FM_PVDDCR_CPU0_P1_R_EN
  W6  PB11C  BI  = FM_GPU_PWR_EN
  W7  VCCIO2_7  POWER  = P3V3_AUX
  W8  PB16D  BI  = PWRGD_P3V3_AUX_R
  W9  PB18D  BI  = FM_CPU0_PWR_GOOD
  W10  PB21B  BI  = FM_PLD_OCP_SFF_PWR_GOOD_R
  W11  VCCIO2_8  POWER  = P3V3_AUX
  W12  GND48  POWER  = GND
  W13  PB30D  BI  = GPU_3V3IO_RSVD0_FFU_ISO_R
  W14  PB33D  BI  = GPU_FPGA_THERM_OVERT_ISO_R_N
  W15  PB35D  BI  = GPU_WP_HW_CTRL_R_N
  W16  VCCIO2_9  POWER  = P3V3_AUX
  W17  PB41D  BI  = RST_PERST_OCP_SFF_N
  W18  PB44D  BI  = FM_AC_PWR_BTN_PLD_ISO_N
  W19  PR30C  BI  = FM_CPU1_FORCE_SELFREFRESH
  W20  PR30B  BI  = FM_FORCE_ALL_PWRON_R
  W21  PR28B  BI  = FM_ROM_SD_LS_OE
  W22  PR25B  BI  = FM_CPU1_NMI_SYNC_FLOOD_N
  Y1  PL29A  BI  = PWRGD_CHGL_CPU0_R2
  Y2  PL29D  BI  = PWRGD_PVDDCR_SOC_P0
  Y3  PL30A  BI  = PWRGD_PVDDCR_CPU0_P0
  Y4  PB7C  BI  = FM_PWRGD_PVDD11_S3_P0
  Y5  PB10C  BI  = FM_PWRGD_PVDDCR_CPU0_P1
  Y6  PB10D  BI  = P12V_SCM_PWRGD_R
  Y7  GND49  POWER  = GND
  Y8  PB18C  BI  = PWRGD_P1V8_AUX_R
  Y9  PB21C  BI  = PWRGD_P1V2_AUX_R
  Y10  PB21D  BI  = BMC_FPGA_LED2
  Y11  PB24D  BI  = FM_LED_PWRGD_PVDDIO_P0
  Y12  PB27A  BI  = FM_LED_PWRGD_PVDD11_S3_P0
  Y13  PB30C  BI  = SWB_HSC_EN_R
  Y14  PB33C  BI  = SWB_HSC_PWRGD_ISO_R
  Y15  PB35C  BI  = GPU_FPGA_OVERT_ISO_R_N
  Y16  GND50  POWER  = GND
  Y17  PB40C  BI  = SW_P3V3_EN
  Y18  PB41C  BI  = FM_SMB_2_ALERT_GPU_ISO_R_N
  Y19  PB44C  BI  = GPU_BASE_STBY_EN_R
  Y20  PR30D  BI  = RST_SMB_RT_R2_N
  Y21  PR29B  BI  = FM_CPU1_PWR_GD_IN
  Y22  PR28A  BI  = FM_ROM_LS_EN

U19  M24M02DRMN6TP  M24M02-DRMN6TP IC  pkg SOIC8XH  page 333
  1  DU1  IN  = NC
  2  DU2  IN  = NC
  3  E2  IN  = U19_E2
  4  VSS  POWER  = GND
  5  SDA  BI  = SMB_RT_CPU1_P1_ROM_SDA
  6  SCL  IN  = SMB_RT_CPU1_P1_ROM_SCL
  7  WC_N  IN  = GND
  8  VCC  POWER  = P1V8_CPU1_RT_1D

U20  M24M02DRMN6TP  M24M02-DRMN6TP IC  pkg SOIC8XH  page 344
  1  DU1  IN  = NC
  2  DU2  IN  = NC
  3  E2  IN  = U20_E2
  4  VSS  POWER  = GND
  5  SDA  BI  = SMB_RT_CPU1_P2_ROM_SDA
  6  SCL  IN  = SMB_RT_CPU1_P2_ROM_SCL
  7  WC_N  IN  = GND
  8  VCC  POWER  = P1V8_CPU1_RT_1D

U21  M24M02DRMN6TP  M24M02-DRMN6TP IC  pkg SOIC8XH  page 355
  1  DU1  IN  = NC
  2  DU2  IN  = NC
  3  E2  IN  = U21_E2
  4  VSS  POWER  = GND
  5  SDA  BI  = SMB_RT_CPU1_P3_ROM_SDA
  6  SCL  IN  = SMB_RT_CPU1_P3_ROM_SCL
  7  WC_N  IN  = GND
  8  VCC  POWER  = P1V8_CPU1_RT_1D

U22  TCA9548APWR  IC  pkg TSSOP24XA  page 185
  1  A0  IN  = RT_ROM_SMB_MUX_ADDR0
  2  A1  IN  = RT_ROM_SMB_MUX_ADDR1
  3  \reset#\  IN  = RST_SMB_RT_ROM_N
  4  SD0  BI  = SMB_RT_CPU1_P0_ROM_MUX_2D_R_SDA
  5  SC0  BI  = SMB_RT_CPU1_P0_ROM_MUX_2D_R_SCL
  6  SD1  BI  = SMB_RT_CPU1_P1_ROM_MUX_2D_R_SDA
  7  SC1  BI  = SMB_RT_CPU1_P1_ROM_MUX_2D_R_SCL
  8  SD2  BI  = SMB_RT_CPU1_P3_ROM_MUX_2D_R_SDA
  9  SC2  BI  = SMB_RT_CPU1_P3_ROM_MUX_2D_R_SCL
  10  SD3  BI  = SMB_RT_CPU1_P2_ROM_MUX_2D_R_SDA
  11  SC3  BI  = SMB_RT_CPU1_P2_ROM_MUX_2D_R_SCL
  12  GND  POWER  = GND
  13  SD4  BI  = SMB_RT_CPU0_P0_ROM_MUX_2D_R_SDA
  14  SC4  BI  = SMB_RT_CPU0_P0_ROM_MUX_2D_R_SCL
  15  SD5  BI  = SMB_RT_CPU0_P1_ROM_MUX_2D_R_SDA
  16  SC5  BI  = SMB_RT_CPU0_P1_ROM_MUX_2D_R_SCL
  17  SD6  BI  = SMB_RT_CPU0_P3_ROM_MUX_2D_R_SDA
  18  SC6  BI  = SMB_RT_CPU0_P3_ROM_MUX_2D_R_SCL
  19  SD7  BI  = SMB_RT_CPU0_P2_ROM_MUX_2D_R_SDA
  20  SC7  BI  = SMB_RT_CPU0_P2_ROM_MUX_2D_R_SCL
  21  A2  IN  = RT_ROM_SMB_MUX_ADDR2
  22  SCL  BI  = SMB_MUX_RT_ROM_SCL
  23  SDA  BI  = SMB_MUX_RT_ROM_SDA
  24  VCC  POWER  = P1V8_AUX

U23  74LVC1G08W57  74LVC1G08W5-7 IC  pkg SOT25-5_0-95_3X1-6  page 136
  1  A  IN  = P12V_OCP_SFF_EN_R3
  2  B  IN  = HP_LVC3_OCP_SFF_PRSNT2
  3  GND  POWER  = GND
  4  Y  OUT  = P12V_OCP_SFF_BUF_EN
  5  VCC  POWER  = P3V3_AUX

U24  MOSFET_N  BSS138K IC  pkg SMLF  page 136
  D  DRAIN  OUT  = HP_LVC3_OCP_SFF_PRSNT2
  G  GATE  IN  = HP_LVC3_OCP_SFF_PRSNT2_N
  S  SOURCE  BI  = GND
